G04*
G04 #@! TF.GenerationSoftware,Altium Limited,Altium Designer,23.0.1 (38)*
G04*
G04 Layer_Color=8388736*
%FSLAX25Y25*%
%MOIN*%
G70*
G04*
G04 #@! TF.SameCoordinates,C48E81DB-6E20-4E2D-80E6-7C5AFAA1A21F*
G04*
G04*
G04 #@! TF.FilePolarity,Positive*
G04*
G01*
G75*
M02*
